FILE_TYPE = CONNECTIVITY;
{Allegro Design Entry HDL 17.2-2016 S081 (4005846) 1/11/2022}
"PAGE_NUMBER" = 19;
0"NC";
1"PU_CPU0_UPI1_AC_COUPLING";
2"PU_CPU0_UPI0_AC_COUPLING";
3"NC_CPU0_DMI_APROBE<1>";
4"NC_CPU0_DMI_APROBE<0>";
5"NC_CPU0_UPI3_APROBE<1>";
6"NC_CPU0_UPI3_APROBE<0>";
7"NC_CPU0_UPI2_APROBE<1>";
8"NC_CPU0_UPI2_APROBE<0>";
9"NC_CPU0_UPI0_APROBE<1>";
10"NC_CPU0_UPI0_APROBE<0>";
11"TP_TRC_CPU0_PTI<15>";
12"TP_TRC_CPU0_PTI<14>";
13"TP_TRC_CPU0_PTI<13>";
14"TP_TRC_CPU0_PTI<12>";
15"TP_TRC_CPU0_PTI<11>";
16"TP_TRC_CPU0_PTI<10>";
17"TP_TRC_CPU0_PTI<9>";
18"TP_TRC_CPU0_PTI<8>";
19"TP_TRC_CPU0_PTI<7>";
20"TP_TRC_CPU0_PTI<6>";
21"TP_TRC_CPU0_PTI<5>";
22"TP_TRC_CPU0_PTI<4>";
23"TP_TRC_CPU0_PTI<3>";
24"TP_TRC_CPU0_PTI<2>";
25"TP_TRC_CPU0_PTI_MON<1>";
26"TP_TP_TRC_CPU0_PTI_MON<0>";
27"TP_TRC_CPU0_PTI0_CLK";
28"TP_TRC_CPU0_PTI1_CLK";
29"TP_TRC_CPU0_PTI<31>";
30"TP_TRC_CPU0_PTI<30>";
31"TP_TRC_CPU0_PTI<29>";
32"TP_TRC_CPU0_PTI<28>";
33"TP_TRC_CPU0_PTI<27>";
34"TP_TRC_CPU0_PTI<26>";
35"TP_TRC_CPU0_PTI<25>";
36"TP_TRC_CPU0_PTI<24>";
37"TP_TRC_CPU0_PTI<23>";
38"TP_TRC_CPU0_PTI<22>";
39"TP_TRC_CPU0_PTI<21>";
40"TP_TRC_CPU0_PTI<20>";
41"TP_TRC_CPU0_PTI<19>";
42"TP_TRC_CPU0_PTI<18>";
43"TP_TRC_CPU0_PTI<17>";
44"TP_TRC_CPU0_PTI<16>";
45"TP_TRC_CPU0_PTI2_CLK";
46"TP_TRC_CPU0_PTI3_CLK";
47"NC_CPU0_PE3_APROBE<0>";
48"NC_CPU0_PE3_APROBE<1>";
49"NC_CPU0_PE4_APROBE<1>";
50"NC_CPU0_PE4_APROBE<0>";
51"NC_CPU0_PE0_APROBE<1>";
52"NC_CPU0_PE0_APROBE<0>";
53"NC_CPU0_UPI1_APROBE<0>";
54"NC_CPU0_PE2_APROBE<1>";
55"NC_CPU0_UPI1_APROBE<1>";
56"NC_CPU0_PE1_APROBE<1>";
57"NC_CPU0_PE2_APROBE<0>";
58"NC_CPU0_PE1_APROBE<0>";
59"PU_CPU0_UPI2_AC_COUPLING";
60"PU_CPU0_UPI3_AC_COUPLING";
%"SOCKET4677_AZIF0045P001C01CS"
"7","(1500,2625)","0","pure_quanta","I1";
;
PART_NUMBER"DGA^7000023"
PART_TYPE"SMLF"
MATERIAL"IO"
VALUE"SOCKET4677_AZIF0045-P001C01CS"
$LOCATION"U2"
CDS_LIB"pure_quanta"
NEEDS_NO_SIZE"TRUE"
CDS_LMAN_SYM_OUTLINE"-1050,1250,1050,-1200"
CDS_LOCATION"U2"
$SEC"7"
CDS_SEC"7";
"UPI3_AC_COUPLING"
$PN"CK71"60;
"UPI2_AC_COUPLING"
$PN"BB65"59;
"UPI1_AC_COUPLING"
$PN"CW19"1;
"UPI0_AC_COUPLING"
$PN"BA23"2;
"RSVD89"
$PN"CE21"58;
"RSVD80"
$PN"CC23"57;
"RSVD79"
$PN"CC21"56;
"RSVD78"
$PN"CA23"55;
"RSVD77"
$PN"CA21"4;
"RSVD75"
$PN"BW23"54;
"RSVD74"
$PN"BW21"3;
"RSVD73"
$PN"BV22"53;
"RSVD66"
$PN"BN21"52;
"RSVD62"
$PN"BL21"51;
"RSVD5"
$PN"AT67"7;
"RSVD3"
$PN"AR17"9;
"RSVD22"
$PN"AV67"50;
"RSVD2"
$PN"AN17"10;
"RSVD14"
$PN"AU68"8;
"RSVD13"
$PN"AU66"49;
"RSVD135"
$PN"CR68"5;
"RSVD130"
$PN"CP69"6;
"RSVD122"
$PN"CM69"48;
"RSVD118"
$PN"CL68"47;
"PTI_DIE01_STB_1"
$PN"BK67"46;
"PTI_DIE01_STB_0"
$PN"BF67"45;
"PTI_DIE010"
$PN"BC70"44;
"PTI_DIE011"
$PN"BE70"43;
"PTI_DIE012"
$PN"BD69"42;
"PTI_DIE013"
$PN"BF69"41;
"PTI_DIE014"
$PN"BH69"40;
"PTI_DIE015"
$PN"BC68"39;
"PTI_DIE016"
$PN"BG68"38;
"PTI_DIE017"
$PN"BD67"37;
"PTI_DIE018"
$PN"BK69"36;
"PTI_DIE019"
$PN"BM69"35;
"PTI_DIE0110"
$PN"BN68"34;
"PTI_DIE0111"
$PN"BG66"33;
"PTI_DIE0112"
$PN"BJ66"32;
"PTI_DIE0113"
$PN"BL66"31;
"PTI_DIE0114"
$PN"BM67"30;
"PTI_DIE0115"
$PN"BN66"29;
"PTI_DIE00_STB_1"
$PN"BY28"28;
"PTI_DIE00_STB_0"
$PN"CB30"27;
"PTI_DIE000"
$PN"CC29"26;
"PTI_DIE001"
$PN"CD28"25;
"PTI_DIE002"
$PN"CC27"24;
"PTI_DIE003"
$PN"BY30"23;
"PTI_DIE004"
$PN"CA29"22;
"PTI_DIE005"
$PN"BV30"21;
"PTI_DIE006"
$PN"CA27"20;
"PTI_DIE007"
$PN"BV28"19;
"PTI_DIE008"
$PN"BU27"18;
"PTI_DIE009"
$PN"BT28"17;
"PTI_DIE0010"
$PN"BU29"16;
"PTI_DIE0011"
$PN"BT30"15;
"PTI_DIE0012"
$PN"BN27"14;
"PTI_DIE0013"
$PN"BP28"13;
"PTI_DIE0014"
$PN"BN29"12;
"PTI_DIE0015"
$PN"BP30"11;
END.
